(kicad_pcb
	(version 20260206)
	(generator "pcbnew")
	(generator_version "10.0")
	(general
		(thickness 1.6)
		(legacy_teardrops no)
	)
	(paper "A4")
	(title_block
		(title "03242023_DA0F0TMBIJ0_F0T_Motherboard_J_brd_V01_OCP.brd")
		(comment 1 "Grand Teton / footprints 2384-2389 of 6105")
	)
	(layers
		(0 "F.Cu" signal "TOP")
		(4 "In1.Cu" signal "GND")
		(6 "In2.Cu" signal "IN1")
		(8 "In3.Cu" signal "GND1")
		(10 "In4.Cu" signal "IN2")
		(12 "In5.Cu" signal "GND2")
		(14 "In6.Cu" signal "IN3")
		(16 "In7.Cu" signal "GND3")
		(18 "In8.Cu" signal "VCC")
		(20 "In9.Cu" signal "VCC1")
		(22 "In10.Cu" signal "GND4")
		(24 "In11.Cu" signal "IN4")
		(26 "In12.Cu" signal "GND5")
		(28 "In13.Cu" signal "IN5")
		(30 "In14.Cu" signal "GND6")
		(32 "In15.Cu" signal "IN6")
		(34 "In16.Cu" signal "GND7")
		(2 "B.Cu" signal "BOTTOM")
		(9 "F.Adhes" user "F.Adhesive")
		(11 "B.Adhes" user "B.Adhesive")
		(13 "F.Paste" user "Package Geometry/Pastemask Top")
		(15 "B.Paste" user "Package Geometry/Pastemask Bottom")
		(5 "F.SilkS" user "Ref Des/Silkscreen Top")
		(7 "B.SilkS" user "Ref Des/Silkscreen Bottom")
		(1 "F.Mask" user "Board Geometry/Soldermask Top")
		(3 "B.Mask" user "Board Geometry/Soldermask Bottom")
		(17 "Dwgs.User" user "User.Drawings")
		(19 "Cmts.User" user "User.Comments")
		(21 "Eco1.User" user "User.Eco1")
		(23 "Eco2.User" user "User.Eco2")
		(25 "Edge.Cuts" user "Board Geometry/Outline")
		(27 "Margin" user)
		(31 "F.CrtYd" user "Package Geometry/Place Bound Top")
		(29 "B.CrtYd" user "Package Geometry/Place Bound Bottom")
		(35 "F.Fab" user "Ref Des/Assembly Top")
		(33 "B.Fab" user "Ref Des/Assembly Bottom")
	)
	(footprint ""
		(layer "F.Cu")
		(at 418.11194 -105.207308 180)
		(property "Reference" "PC2159"
			(at 0 0 180)
			(layer "F.SilkS")
			(hide yes)
			(effects
				(font
					(size 1.27 1.27)
				)
			)
		)
		(property "Value" ""
			(at 0 0 180)
			(layer "F.Fab")
			(effects
				(font
					(size 1.27 1.27)
				)
			)
		)
		(duplicate_pad_numbers_are_jumpers no)
		(fp_line
			(start 0.7874 0.4064)
			(end -0.7874 0.4064)
			(stroke
				(width 0.1524)
				(type default)
			)
			(layer "F.SilkS")
		)
		(fp_line
			(start 0.7874 -0.4064)
			(end 0.7874 0.4064)
			(stroke
				(width 0.1524)
				(type default)
			)
			(layer "F.SilkS")
		)
		(fp_line
			(start -0.7874 0.4064)
			(end -0.7874 -0.4064)
			(stroke
				(width 0.1524)
				(type default)
			)
			(layer "F.SilkS")
		)
		(fp_line
			(start -0.7874 -0.4064)
			(end 0.7874 -0.4064)
			(stroke
				(width 0.1524)
				(type default)
			)
			(layer "F.SilkS")
		)
		(fp_line
			(start 0.67945 0.3048)
			(end 0.120396 0.3048)
			(stroke
				(width 0.1)
				(type default)
			)
			(layer "F.Fab")
		)
		(fp_line
			(start 0.67945 -0.3048)
			(end 0.67945 0.3048)
			(stroke
				(width 0.1)
				(type default)
			)
			(layer "F.Fab")
		)
		(fp_line
			(start 0.12065 -0.2794)
			(end 0.12065 -0.3048)
			(stroke
				(width 0.1)
				(type default)
			)
			(layer "F.Fab")
		)
		(fp_line
			(start 0.12065 -0.3048)
			(end 0.67945 -0.3048)
			(stroke
				(width 0.1)
				(type default)
			)
			(layer "F.Fab")
		)
		(fp_line
			(start 0.120396 0.3048)
			(end 0.120396 0.2794)
			(stroke
				(width 0.1)
				(type default)
			)
			(layer "F.Fab")
		)
		(fp_line
			(start 0.120396 0.2794)
			(end -0.12065 0.2794)
			(stroke
				(width 0.1)
				(type default)
			)
			(layer "F.Fab")
		)
		(fp_line
			(start -0.12065 0.3048)
			(end -0.67945 0.3048)
			(stroke
				(width 0.1)
				(type default)
			)
			(layer "F.Fab")
		)
		(fp_line
			(start -0.12065 0.2794)
			(end -0.12065 0.3048)
			(stroke
				(width 0.1)
				(type default)
			)
			(layer "F.Fab")
		)
		(fp_line
			(start -0.12065 -0.2794)
			(end 0.12065 -0.2794)
			(stroke
				(width 0.1)
				(type default)
			)
			(layer "F.Fab")
		)
		(fp_line
			(start -0.12065 -0.305054)
			(end -0.12065 -0.2794)
			(stroke
				(width 0.1)
				(type default)
			)
			(layer "F.Fab")
		)
		(fp_line
			(start -0.67945 0.3048)
			(end -0.67945 -0.305054)
			(stroke
				(width 0.1)
				(type default)
			)
			(layer "F.Fab")
		)
		(fp_line
			(start -0.67945 -0.305054)
			(end -0.12065 -0.305054)
			(stroke
				(width 0.1)
				(type default)
			)
			(layer "F.Fab")
		)
		(pad "1" smd circle
			(at -0.40005 0 180)
			(size 0 0)
			(layers "F.Cu" "F.Mask" "F.Paste")
			(net "P3V3_AUX")
		)
		(pad "2" smd circle
			(at 0.40005 0 180)
			(size 0 0)
			(layers "F.Cu" "F.Mask" "F.Paste")
			(net "GND")
		)
	)
	(footprint ""
		(layer "F.Cu")
		(at 136.6266 -28.578048 180)
		(property "Reference" "R4281"
			(at 0 0 180)
			(layer "F.SilkS")
			(hide yes)
			(effects
				(font
					(size 1.27 1.27)
				)
			)
		)
		(property "Value" ""
			(at 0 0 180)
			(layer "F.Fab")
			(effects
				(font
					(size 1.27 1.27)
				)
			)
		)
		(duplicate_pad_numbers_are_jumpers no)
		(fp_line
			(start 0.7874 0.4064)
			(end -0.7874 0.4064)
			(stroke
				(width 0.1524)
				(type default)
			)
			(layer "F.SilkS")
		)
		(fp_line
			(start 0.7874 -0.4064)
			(end 0.7874 0.4064)
			(stroke
				(width 0.1524)
				(type default)
			)
			(layer "F.SilkS")
		)
		(fp_line
			(start -0.7874 0.4064)
			(end -0.7874 -0.4064)
			(stroke
				(width 0.1524)
				(type default)
			)
			(layer "F.SilkS")
		)
		(fp_line
			(start -0.7874 -0.4064)
			(end 0.7874 -0.4064)
			(stroke
				(width 0.1524)
				(type default)
			)
			(layer "F.SilkS")
		)
		(fp_line
			(start 0.67945 0.3048)
			(end 0.120396 0.3048)
			(stroke
				(width 0.1)
				(type default)
			)
			(layer "F.Fab")
		)
		(fp_line
			(start 0.67945 -0.3048)
			(end 0.67945 0.3048)
			(stroke
				(width 0.1)
				(type default)
			)
			(layer "F.Fab")
		)
		(fp_line
			(start 0.12065 -0.2794)
			(end 0.12065 -0.3048)
			(stroke
				(width 0.1)
				(type default)
			)
			(layer "F.Fab")
		)
		(fp_line
			(start 0.12065 -0.3048)
			(end 0.67945 -0.3048)
			(stroke
				(width 0.1)
				(type default)
			)
			(layer "F.Fab")
		)
		(fp_line
			(start 0.120396 0.3048)
			(end 0.120396 0.2794)
			(stroke
				(width 0.1)
				(type default)
			)
			(layer "F.Fab")
		)
		(fp_line
			(start 0.120396 0.2794)
			(end -0.12065 0.2794)
			(stroke
				(width 0.1)
				(type default)
			)
			(layer "F.Fab")
		)
		(fp_line
			(start -0.12065 0.3048)
			(end -0.67945 0.3048)
			(stroke
				(width 0.1)
				(type default)
			)
			(layer "F.Fab")
		)
		(fp_line
			(start -0.12065 0.2794)
			(end -0.12065 0.3048)
			(stroke
				(width 0.1)
				(type default)
			)
			(layer "F.Fab")
		)
		(fp_line
			(start -0.12065 -0.2794)
			(end 0.12065 -0.2794)
			(stroke
				(width 0.1)
				(type default)
			)
			(layer "F.Fab")
		)
		(fp_line
			(start -0.12065 -0.305054)
			(end -0.12065 -0.2794)
			(stroke
				(width 0.1)
				(type default)
			)
			(layer "F.Fab")
		)
		(fp_line
			(start -0.67945 0.3048)
			(end -0.67945 -0.305054)
			(stroke
				(width 0.1)
				(type default)
			)
			(layer "F.Fab")
		)
		(fp_line
			(start -0.67945 -0.305054)
			(end -0.12065 -0.305054)
			(stroke
				(width 0.1)
				(type default)
			)
			(layer "F.Fab")
		)
		(pad "1" smd circle
			(at -0.40005 0 180)
			(size 0 0)
			(layers "F.Cu" "F.Mask" "F.Paste")
			(net "P3V3_AUX")
		)
		(pad "2" smd circle
			(at 0.40005 0 180)
			(size 0 0)
			(layers "F.Cu" "F.Mask" "F.Paste")
			(net "FM_USB3_1_EQB")
		)
	)
	(footprint ""
		(layer "F.Cu")
		(at 162.34283 -76.770738)
		(property "Reference" "R2209"
			(at 0 0 0)
			(layer "F.SilkS")
			(hide yes)
			(effects
				(font
					(size 1.27 1.27)
				)
			)
		)
		(property "Value" ""
			(at 0 0 0)
			(layer "F.Fab")
			(effects
				(font
					(size 1.27 1.27)
				)
			)
		)
		(duplicate_pad_numbers_are_jumpers no)
		(fp_line
			(start -0.7874 -0.4064)
			(end 0.7874 -0.4064)
			(stroke
				(width 0.1524)
				(type default)
			)
			(layer "F.SilkS")
		)
		(fp_line
			(start -0.7874 0.4064)
			(end -0.7874 -0.4064)
			(stroke
				(width 0.1524)
				(type default)
			)
			(layer "F.SilkS")
		)
		(fp_line
			(start 0.7874 -0.4064)
			(end 0.7874 0.4064)
			(stroke
				(width 0.1524)
				(type default)
			)
			(layer "F.SilkS")
		)
		(fp_line
			(start 0.7874 0.4064)
			(end -0.7874 0.4064)
			(stroke
				(width 0.1524)
				(type default)
			)
			(layer "F.SilkS")
		)
		(fp_line
			(start -0.67945 -0.305054)
			(end -0.12065 -0.305054)
			(stroke
				(width 0.1)
				(type default)
			)
			(layer "F.Fab")
		)
		(fp_line
			(start -0.67945 0.3048)
			(end -0.67945 -0.305054)
			(stroke
				(width 0.1)
				(type default)
			)
			(layer "F.Fab")
		)
		(fp_line
			(start -0.12065 -0.305054)
			(end -0.12065 -0.2794)
			(stroke
				(width 0.1)
				(type default)
			)
			(layer "F.Fab")
		)
		(fp_line
			(start -0.12065 -0.2794)
			(end 0.12065 -0.2794)
			(stroke
				(width 0.1)
				(type default)
			)
			(layer "F.Fab")
		)
		(fp_line
			(start -0.12065 0.2794)
			(end -0.12065 0.3048)
			(stroke
				(width 0.1)
				(type default)
			)
			(layer "F.Fab")
		)
		(fp_line
			(start -0.12065 0.3048)
			(end -0.67945 0.3048)
			(stroke
				(width 0.1)
				(type default)
			)
			(layer "F.Fab")
		)
		(fp_line
			(start 0.120396 0.2794)
			(end -0.12065 0.2794)
			(stroke
				(width 0.1)
				(type default)
			)
			(layer "F.Fab")
		)
		(fp_line
			(start 0.120396 0.3048)
			(end 0.120396 0.2794)
			(stroke
				(width 0.1)
				(type default)
			)
			(layer "F.Fab")
		)
		(fp_line
			(start 0.12065 -0.3048)
			(end 0.67945 -0.3048)
			(stroke
				(width 0.1)
				(type default)
			)
			(layer "F.Fab")
		)
		(fp_line
			(start 0.12065 -0.2794)
			(end 0.12065 -0.3048)
			(stroke
				(width 0.1)
				(type default)
			)
			(layer "F.Fab")
		)
		(fp_line
			(start 0.67945 -0.3048)
			(end 0.67945 0.3048)
			(stroke
				(width 0.1)
				(type default)
			)
			(layer "F.Fab")
		)
		(fp_line
			(start 0.67945 0.3048)
			(end 0.120396 0.3048)
			(stroke
				(width 0.1)
				(type default)
			)
			(layer "F.Fab")
		)
		(pad "1" smd circle
			(at -0.40005 0)
			(size 0 0)
			(layers "F.Cu" "F.Mask" "F.Paste")
			(net "SMB_S3M_CPU0_3V3AUX_SCL_R")
		)
		(pad "2" smd circle
			(at 0.40005 0)
			(size 0 0)
			(layers "F.Cu" "F.Mask" "F.Paste")
			(net "SMB_S3M_CPU0_3V3AUX_SCL")
		)
	)
	(footprint ""
		(layer "F.Cu")
		(at 214.43188 -47.335948 90)
		(property "Reference" "R3588"
			(at 0 0 90)
			(layer "F.SilkS")
			(hide yes)
			(effects
				(font
					(size 1.27 1.27)
				)
			)
		)
		(property "Value" ""
			(at 0 0 90)
			(layer "F.Fab")
			(effects
				(font
					(size 1.27 1.27)
				)
			)
		)
		(duplicate_pad_numbers_are_jumpers no)
		(fp_line
			(start 0.7874 -0.4064)
			(end 0.7874 0.4064)
			(stroke
				(width 0.1524)
				(type default)
			)
			(layer "F.SilkS")
		)
		(fp_line
			(start -0.7874 -0.4064)
			(end 0.7874 -0.4064)
			(stroke
				(width 0.1524)
				(type default)
			)
			(layer "F.SilkS")
		)
		(fp_line
			(start 0.7874 0.4064)
			(end -0.7874 0.4064)
			(stroke
				(width 0.1524)
				(type default)
			)
			(layer "F.SilkS")
		)
		(fp_line
			(start -0.7874 0.4064)
			(end -0.7874 -0.4064)
			(stroke
				(width 0.1524)
				(type default)
			)
			(layer "F.SilkS")
		)
		(fp_line
			(start -0.12065 -0.305054)
			(end -0.12065 -0.2794)
			(stroke
				(width 0.1)
				(type default)
			)
			(layer "F.Fab")
		)
		(fp_line
			(start -0.67945 -0.305054)
			(end -0.12065 -0.305054)
			(stroke
				(width 0.1)
				(type default)
			)
			(layer "F.Fab")
		)
		(fp_line
			(start 0.67945 -0.3048)
			(end 0.67945 0.3048)
			(stroke
				(width 0.1)
				(type default)
			)
			(layer "F.Fab")
		)
		(fp_line
			(start 0.12065 -0.3048)
			(end 0.67945 -0.3048)
			(stroke
				(width 0.1)
				(type default)
			)
			(layer "F.Fab")
		)
		(fp_line
			(start 0.12065 -0.2794)
			(end 0.12065 -0.3048)
			(stroke
				(width 0.1)
				(type default)
			)
			(layer "F.Fab")
		)
		(fp_line
			(start -0.12065 -0.2794)
			(end 0.12065 -0.2794)
			(stroke
				(width 0.1)
				(type default)
			)
			(layer "F.Fab")
		)
		(fp_line
			(start 0.120396 0.2794)
			(end -0.12065 0.2794)
			(stroke
				(width 0.1)
				(type default)
			)
			(layer "F.Fab")
		)
		(fp_line
			(start -0.12065 0.2794)
			(end -0.12065 0.3048)
			(stroke
				(width 0.1)
				(type default)
			)
			(layer "F.Fab")
		)
		(fp_line
			(start 0.67945 0.3048)
			(end 0.120396 0.3048)
			(stroke
				(width 0.1)
				(type default)
			)
			(layer "F.Fab")
		)
		(fp_line
			(start 0.120396 0.3048)
			(end 0.120396 0.2794)
			(stroke
				(width 0.1)
				(type default)
			)
			(layer "F.Fab")
		)
		(fp_line
			(start -0.12065 0.3048)
			(end -0.67945 0.3048)
			(stroke
				(width 0.1)
				(type default)
			)
			(layer "F.Fab")
		)
		(fp_line
			(start -0.67945 0.3048)
			(end -0.67945 -0.305054)
			(stroke
				(width 0.1)
				(type default)
			)
			(layer "F.Fab")
		)
		(pad "1" smd circle
			(at -0.40005 0 90)
			(size 0 0)
			(layers "F.Cu" "F.Mask" "F.Paste")
			(net "SMB_INA230_3V3AUX_SCL")
		)
		(pad "2" smd circle
			(at 0.40005 0 90)
			(size 0 0)
			(layers "F.Cu" "F.Mask" "F.Paste")
			(net "SMB_INA230_2_3V3AUX_SCL_R")
		)
	)
	(footprint ""
		(layer "F.Cu")
		(at 309.519066 -43.92803 180)
		(property "Reference" "R1955"
			(at 0 0 180)
			(layer "F.SilkS")
			(hide yes)
			(effects
				(font
					(size 1.27 1.27)
				)
			)
		)
		(property "Value" ""
			(at 0 0 180)
			(layer "F.Fab")
			(effects
				(font
					(size 1.27 1.27)
				)
			)
		)
		(duplicate_pad_numbers_are_jumpers no)
		(fp_line
			(start 0.7874 0.4064)
			(end -0.7874 0.4064)
			(stroke
				(width 0.1524)
				(type default)
			)
			(layer "F.SilkS")
		)
		(fp_line
			(start 0.7874 -0.4064)
			(end 0.7874 0.4064)
			(stroke
				(width 0.1524)
				(type default)
			)
			(layer "F.SilkS")
		)
		(fp_line
			(start -0.7874 0.4064)
			(end -0.7874 -0.4064)
			(stroke
				(width 0.1524)
				(type default)
			)
			(layer "F.SilkS")
		)
		(fp_line
			(start -0.7874 -0.4064)
			(end 0.7874 -0.4064)
			(stroke
				(width 0.1524)
				(type default)
			)
			(layer "F.SilkS")
		)
		(fp_line
			(start 0.67945 0.3048)
			(end 0.120396 0.3048)
			(stroke
				(width 0.1)
				(type default)
			)
			(layer "F.Fab")
		)
		(fp_line
			(start 0.67945 -0.3048)
			(end 0.67945 0.3048)
			(stroke
				(width 0.1)
				(type default)
			)
			(layer "F.Fab")
		)
		(fp_line
			(start 0.12065 -0.2794)
			(end 0.12065 -0.3048)
			(stroke
				(width 0.1)
				(type default)
			)
			(layer "F.Fab")
		)
		(fp_line
			(start 0.12065 -0.3048)
			(end 0.67945 -0.3048)
			(stroke
				(width 0.1)
				(type default)
			)
			(layer "F.Fab")
		)
		(fp_line
			(start 0.120396 0.3048)
			(end 0.120396 0.2794)
			(stroke
				(width 0.1)
				(type default)
			)
			(layer "F.Fab")
		)
		(fp_line
			(start 0.120396 0.2794)
			(end -0.12065 0.2794)
			(stroke
				(width 0.1)
				(type default)
			)
			(layer "F.Fab")
		)
		(fp_line
			(start -0.12065 0.3048)
			(end -0.67945 0.3048)
			(stroke
				(width 0.1)
				(type default)
			)
			(layer "F.Fab")
		)
		(fp_line
			(start -0.12065 0.2794)
			(end -0.12065 0.3048)
			(stroke
				(width 0.1)
				(type default)
			)
			(layer "F.Fab")
		)
		(fp_line
			(start -0.12065 -0.2794)
			(end 0.12065 -0.2794)
			(stroke
				(width 0.1)
				(type default)
			)
			(layer "F.Fab")
		)
		(fp_line
			(start -0.12065 -0.305054)
			(end -0.12065 -0.2794)
			(stroke
				(width 0.1)
				(type default)
			)
			(layer "F.Fab")
		)
		(fp_line
			(start -0.67945 0.3048)
			(end -0.67945 -0.305054)
			(stroke
				(width 0.1)
				(type default)
			)
			(layer "F.Fab")
		)
		(fp_line
			(start -0.67945 -0.305054)
			(end -0.12065 -0.305054)
			(stroke
				(width 0.1)
				(type default)
			)
			(layer "F.Fab")
		)
		(pad "1" smd circle
			(at -0.40005 0 180)
			(size 0 0)
			(layers "F.Cu" "F.Mask" "F.Paste")
			(net "P3V3_AUX")
		)
		(pad "2" smd circle
			(at 0.40005 0 180)
			(size 0 0)
			(layers "F.Cu" "F.Mask" "F.Paste")
			(net "FM_PCHHOT_N")
		)
	)
	(footprint ""
		(layer "F.Cu")
		(at 179.352448 -403.271482 180)
		(property "Reference" "PC2187"
			(at 0 0 180)
			(layer "F.SilkS")
			(hide yes)
			(effects
				(font
					(size 1.27 1.27)
				)
			)
		)
		(property "Value" ""
			(at 0 0 180)
			(layer "F.Fab")
			(effects
				(font
					(size 1.27 1.27)
				)
			)
		)
		(duplicate_pad_numbers_are_jumpers no)
		(fp_line
			(start 0.7874 0.4064)
			(end -0.7874 0.4064)
			(stroke
				(width 0.1524)
				(type default)
			)
			(layer "F.SilkS")
		)
		(fp_line
			(start 0.7874 -0.4064)
			(end 0.7874 0.4064)
			(stroke
				(width 0.1524)
				(type default)
			)
			(layer "F.SilkS")
		)
		(fp_line
			(start -0.7874 0.4064)
			(end -0.7874 -0.4064)
			(stroke
				(width 0.1524)
				(type default)
			)
			(layer "F.SilkS")
		)
		(fp_line
			(start -0.7874 -0.4064)
			(end 0.7874 -0.4064)
			(stroke
				(width 0.1524)
				(type default)
			)
			(layer "F.SilkS")
		)
		(fp_line
			(start 0.67945 0.3048)
			(end 0.120396 0.3048)
			(stroke
				(width 0.1)
				(type default)
			)
			(layer "F.Fab")
		)
		(fp_line
			(start 0.67945 -0.3048)
			(end 0.67945 0.3048)
			(stroke
				(width 0.1)
				(type default)
			)
			(layer "F.Fab")
		)
		(fp_line
			(start 0.12065 -0.2794)
			(end 0.12065 -0.3048)
			(stroke
				(width 0.1)
				(type default)
			)
			(layer "F.Fab")
		)
		(fp_line
			(start 0.12065 -0.3048)
			(end 0.67945 -0.3048)
			(stroke
				(width 0.1)
				(type default)
			)
			(layer "F.Fab")
		)
		(fp_line
			(start 0.120396 0.3048)
			(end 0.120396 0.2794)
			(stroke
				(width 0.1)
				(type default)
			)
			(layer "F.Fab")
		)
		(fp_line
			(start 0.120396 0.2794)
			(end -0.12065 0.2794)
			(stroke
				(width 0.1)
				(type default)
			)
			(layer "F.Fab")
		)
		(fp_line
			(start -0.12065 0.3048)
			(end -0.67945 0.3048)
			(stroke
				(width 0.1)
				(type default)
			)
			(layer "F.Fab")
		)
		(fp_line
			(start -0.12065 0.2794)
			(end -0.12065 0.3048)
			(stroke
				(width 0.1)
				(type default)
			)
			(layer "F.Fab")
		)
		(fp_line
			(start -0.12065 -0.2794)
			(end 0.12065 -0.2794)
			(stroke
				(width 0.1)
				(type default)
			)
			(layer "F.Fab")
		)
		(fp_line
			(start -0.12065 -0.305054)
			(end -0.12065 -0.2794)
			(stroke
				(width 0.1)
				(type default)
			)
			(layer "F.Fab")
		)
		(fp_line
			(start -0.67945 0.3048)
			(end -0.67945 -0.305054)
			(stroke
				(width 0.1)
				(type default)
			)
			(layer "F.Fab")
		)
		(fp_line
			(start -0.67945 -0.305054)
			(end -0.12065 -0.305054)
			(stroke
				(width 0.1)
				(type default)
			)
			(layer "F.Fab")
		)
		(pad "1" smd circle
			(at -0.40005 0 180)
			(size 0 0)
			(layers "F.Cu" "F.Mask" "F.Paste")
			(net "HSC_VDD_R")
		)
		(pad "2" smd circle
			(at 0.40005 0 180)
			(size 0 0)
			(layers "F.Cu" "F.Mask" "F.Paste")
			(net "AGND_HSC")
		)
	)
)
